# SCM (Grand Teton) — schematic netlist excerpt (pin names and nets, part order shuffled) for the footprints in the layout excerpt that follows; sources: Cadence DE-HDL packaged netlist, KiCad conversion of 12092022_DA0F0TMDCD0_F0T_Management_Board_D_brd_V3_OCP.brd

R807  Q_RES  33.2 1% CHIP  pkg 0402LF  page 34 : A = CLK_25M_OSC_FPGA_R ; B = CLK_25M_OSC_FPGA
R694  Q_RES  100 1% CHIP  pkg 0402LF  page 29 : A = USB3_MUX_PD ; B = GND

(kicad_pcb
	(version 20260206)
	(generator "pcbnew")
	(generator_version "10.0")
	(general
		(thickness 1.6)
		(legacy_teardrops no)
	)
	(paper "A4")
	(title_block
		(title "12092022_DA0F0TMDCD0_F0T_Management_Board_D_brd_V3_OCP.brd")
		(comment 1 "Grand Teton / footprints 1261-1262 of 1440")
	)
	(layers
		(0 "F.Cu" signal "TOP")
		(4 "In1.Cu" signal "GND")
		(6 "In2.Cu" signal "IN1")
		(8 "In3.Cu" signal "GND1")
		(10 "In4.Cu" signal "IN2")
		(12 "In5.Cu" signal "VCC")
		(14 "In6.Cu" signal "VCC1")
		(16 "In7.Cu" signal "IN3")
		(18 "In8.Cu" signal "GND2")
		(20 "In9.Cu" signal "IN4")
		(22 "In10.Cu" signal "GND3")
		(2 "B.Cu" signal "BOTTOM")
		(9 "F.Adhes" user "F.Adhesive")
		(11 "B.Adhes" user "B.Adhesive")
		(13 "F.Paste" user "Package Geometry/Pastemask Top")
		(15 "B.Paste" user "Package Geometry/Pastemask Bottom")
		(5 "F.SilkS" user "Ref Des/Silkscreen Top")
		(7 "B.SilkS" user "Ref Des/Silkscreen Bottom")
		(1 "F.Mask" user "Board Geometry/Soldermask Top")
		(3 "B.Mask" user "Board Geometry/Soldermask Bottom")
		(17 "Dwgs.User" user "User.Drawings")
		(19 "Cmts.User" user "User.Comments")
		(21 "Eco1.User" user "User.Eco1")
		(23 "Eco2.User" user "User.Eco2")
		(25 "Edge.Cuts" user "Board Geometry/Outline")
		(27 "Margin" user)
		(31 "F.CrtYd" user "Package Geometry/Place Bound Top")
		(29 "B.CrtYd" user "Package Geometry/Place Bound Bottom")
		(35 "F.Fab" user "Ref Des/Assembly Top")
		(33 "B.Fab" user "Ref Des/Assembly Bottom")
	)
	(footprint ""
		(layer "B.Cu")
		(at 22.5298 -83.693 -90)
		(property "Reference" "R807"
			(at 0 0 90)
			(layer "B.SilkS")
			(hide yes)
			(effects
				(font
					(size 1.27 1.27)
				)
				(justify mirror)
			)
		)
		(property "Value" ""
			(at 0 0 90)
			(layer "B.Fab")
			(effects
				(font
					(size 1.27 1.27)
				)
				(justify mirror)
			)
		)
		(duplicate_pad_numbers_are_jumpers no)
		(fp_line
			(start -0.7874 0.4064)
			(end 0.7874 0.4064)
			(stroke
				(width 0.1524)
				(type default)
			)
			(layer "B.SilkS")
		)
		(fp_line
			(start 0.7874 0.4064)
			(end 0.7874 -0.4064)
			(stroke
				(width 0.1524)
				(type default)
			)
			(layer "B.SilkS")
		)
		(fp_line
			(start -0.7874 -0.4064)
			(end -0.7874 0.4064)
			(stroke
				(width 0.1524)
				(type default)
			)
			(layer "B.SilkS")
		)
		(fp_line
			(start 0.7874 -0.4064)
			(end -0.7874 -0.4064)
			(stroke
				(width 0.1524)
				(type default)
			)
			(layer "B.SilkS")
		)
		(fp_line
			(start -0.67945 0.3048)
			(end -0.120396 0.3048)
			(stroke
				(width 0.1)
				(type default)
			)
			(layer "B.Fab")
		)
		(fp_line
			(start -0.120396 0.3048)
			(end -0.120396 0.2794)
			(stroke
				(width 0.1)
				(type default)
			)
			(layer "B.Fab")
		)
		(fp_line
			(start 0.12065 0.3048)
			(end 0.67945 0.3048)
			(stroke
				(width 0.1)
				(type default)
			)
			(layer "B.Fab")
		)
		(fp_line
			(start 0.67945 0.3048)
			(end 0.67945 -0.305054)
			(stroke
				(width 0.1)
				(type default)
			)
			(layer "B.Fab")
		)
		(fp_line
			(start -0.120396 0.2794)
			(end 0.12065 0.2794)
			(stroke
				(width 0.1)
				(type default)
			)
			(layer "B.Fab")
		)
		(fp_line
			(start 0.12065 0.2794)
			(end 0.12065 0.3048)
			(stroke
				(width 0.1)
				(type default)
			)
			(layer "B.Fab")
		)
		(fp_line
			(start -0.12065 -0.2794)
			(end -0.12065 -0.3048)
			(stroke
				(width 0.1)
				(type default)
			)
			(layer "B.Fab")
		)
		(fp_line
			(start 0.12065 -0.2794)
			(end -0.12065 -0.2794)
			(stroke
				(width 0.1)
				(type default)
			)
			(layer "B.Fab")
		)
		(fp_line
			(start -0.67945 -0.3048)
			(end -0.67945 0.3048)
			(stroke
				(width 0.1)
				(type default)
			)
			(layer "B.Fab")
		)
		(fp_line
			(start -0.12065 -0.3048)
			(end -0.67945 -0.3048)
			(stroke
				(width 0.1)
				(type default)
			)
			(layer "B.Fab")
		)
		(fp_line
			(start 0.12065 -0.305054)
			(end 0.12065 -0.2794)
			(stroke
				(width 0.1)
				(type default)
			)
			(layer "B.Fab")
		)
		(fp_line
			(start 0.67945 -0.305054)
			(end 0.12065 -0.305054)
			(stroke
				(width 0.1)
				(type default)
			)
			(layer "B.Fab")
		)
		(pad "1" smd circle
			(at 0.40005 0 90)
			(size 0 0)
			(layers "B.Cu" "B.Mask" "B.Paste")
			(net "CLK_25M_OSC_FPGA_R")
		)
		(pad "2" smd circle
			(at -0.40005 0 90)
			(size 0 0)
			(layers "B.Cu" "B.Mask" "B.Paste")
			(net "CLK_25M_OSC_FPGA")
		)
	)
	(footprint ""
		(layer "B.Cu")
		(at 43.8912 -88.4936 90)
		(property "Reference" "R694"
			(at 0 0 90)
			(layer "B.SilkS")
			(hide yes)
			(effects
				(font
					(size 1.27 1.27)
				)
				(justify mirror)
			)
		)
		(property "Value" ""
			(at 0 0 90)
			(layer "B.Fab")
			(effects
				(font
					(size 1.27 1.27)
				)
				(justify mirror)
			)
		)
		(duplicate_pad_numbers_are_jumpers no)
		(fp_line
			(start 0.7874 -0.4064)
			(end -0.7874 -0.4064)
			(stroke
				(width 0.1524)
				(type default)
			)
			(layer "B.SilkS")
		)
		(fp_line
			(start -0.7874 -0.4064)
			(end -0.7874 0.4064)
			(stroke
				(width 0.1524)
				(type default)
			)
			(layer "B.SilkS")
		)
		(fp_line
			(start 0.7874 0.4064)
			(end 0.7874 -0.4064)
			(stroke
				(width 0.1524)
				(type default)
			)
			(layer "B.SilkS")
		)
		(fp_line
			(start -0.7874 0.4064)
			(end 0.7874 0.4064)
			(stroke
				(width 0.1524)
				(type default)
			)
			(layer "B.SilkS")
		)
		(fp_line
			(start 0.67945 -0.305054)
			(end 0.12065 -0.305054)
			(stroke
				(width 0.1)
				(type default)
			)
			(layer "B.Fab")
		)
		(fp_line
			(start 0.12065 -0.305054)
			(end 0.12065 -0.2794)
			(stroke
				(width 0.1)
				(type default)
			)
			(layer "B.Fab")
		)
		(fp_line
			(start -0.12065 -0.3048)
			(end -0.67945 -0.3048)
			(stroke
				(width 0.1)
				(type default)
			)
			(layer "B.Fab")
		)
		(fp_line
			(start -0.67945 -0.3048)
			(end -0.67945 0.3048)
			(stroke
				(width 0.1)
				(type default)
			)
			(layer "B.Fab")
		)
		(fp_line
			(start 0.12065 -0.2794)
			(end -0.12065 -0.2794)
			(stroke
				(width 0.1)
				(type default)
			)
			(layer "B.Fab")
		)
		(fp_line
			(start -0.12065 -0.2794)
			(end -0.12065 -0.3048)
			(stroke
				(width 0.1)
				(type default)
			)
			(layer "B.Fab")
		)
		(fp_line
			(start 0.12065 0.2794)
			(end 0.12065 0.3048)
			(stroke
				(width 0.1)
				(type default)
			)
			(layer "B.Fab")
		)
		(fp_line
			(start -0.120396 0.2794)
			(end 0.12065 0.2794)
			(stroke
				(width 0.1)
				(type default)
			)
			(layer "B.Fab")
		)
		(fp_line
			(start 0.67945 0.3048)
			(end 0.67945 -0.305054)
			(stroke
				(width 0.1)
				(type default)
			)
			(layer "B.Fab")
		)
		(fp_line
			(start 0.12065 0.3048)
			(end 0.67945 0.3048)
			(stroke
				(width 0.1)
				(type default)
			)
			(layer "B.Fab")
		)
		(fp_line
			(start -0.120396 0.3048)
			(end -0.120396 0.2794)
			(stroke
				(width 0.1)
				(type default)
			)
			(layer "B.Fab")
		)
		(fp_line
			(start -0.67945 0.3048)
			(end -0.120396 0.3048)
			(stroke
				(width 0.1)
				(type default)
			)
			(layer "B.Fab")
		)
		(pad "1" smd circle
			(at 0.40005 0 270)
			(size 0 0)
			(layers "B.Cu" "B.Mask" "B.Paste")
			(net "USB3_MUX_PD")
		)
		(pad "2" smd circle
			(at -0.40005 0 270)
			(size 0 0)
			(layers "B.Cu" "B.Mask" "B.Paste")
			(net "GND")
		)
	)
)
